(kicad_pcb
	(version 20260206)
	(generator "pcbnew")
	(generator_version "10.0")
	(general
		(thickness 1.6)
		(legacy_teardrops no)
	)
	(paper "A4")
	(title_block
		(title "03242023_DA0F0TMBIJ0_F0T_Motherboard_J_brd_V01_OCP.brd")
		(comment 1 "Grand Teton / footprints 2565-2570 of 6105")
	)
	(layers
		(0 "F.Cu" signal "TOP")
		(4 "In1.Cu" signal "GND")
		(6 "In2.Cu" signal "IN1")
		(8 "In3.Cu" signal "GND1")
		(10 "In4.Cu" signal "IN2")
		(12 "In5.Cu" signal "GND2")
		(14 "In6.Cu" signal "IN3")
		(16 "In7.Cu" signal "GND3")
		(18 "In8.Cu" signal "VCC")
		(20 "In9.Cu" signal "VCC1")
		(22 "In10.Cu" signal "GND4")
		(24 "In11.Cu" signal "IN4")
		(26 "In12.Cu" signal "GND5")
		(28 "In13.Cu" signal "IN5")
		(30 "In14.Cu" signal "GND6")
		(32 "In15.Cu" signal "IN6")
		(34 "In16.Cu" signal "GND7")
		(2 "B.Cu" signal "BOTTOM")
		(9 "F.Adhes" user "F.Adhesive")
		(11 "B.Adhes" user "B.Adhesive")
		(13 "F.Paste" user "Package Geometry/Pastemask Top")
		(15 "B.Paste" user "Package Geometry/Pastemask Bottom")
		(5 "F.SilkS" user "Ref Des/Silkscreen Top")
		(7 "B.SilkS" user "Ref Des/Silkscreen Bottom")
		(1 "F.Mask" user "Board Geometry/Soldermask Top")
		(3 "B.Mask" user "Board Geometry/Soldermask Bottom")
		(17 "Dwgs.User" user "User.Drawings")
		(19 "Cmts.User" user "User.Comments")
		(21 "Eco1.User" user "User.Eco1")
		(23 "Eco2.User" user "User.Eco2")
		(25 "Edge.Cuts" user "Board Geometry/Outline")
		(27 "Margin" user)
		(31 "F.CrtYd" user "Package Geometry/Place Bound Top")
		(29 "B.CrtYd" user "Package Geometry/Place Bound Bottom")
		(35 "F.Fab" user "Ref Des/Assembly Top")
		(33 "B.Fab" user "Ref Des/Assembly Bottom")
	)
	(footprint ""
		(layer "F.Cu")
		(at 468.49284 -43.735498 180)
		(property "Reference" "R2488"
			(at 0 0 180)
			(layer "F.SilkS")
			(hide yes)
			(effects
				(font
					(size 1.27 1.27)
				)
			)
		)
		(property "Value" ""
			(at 0 0 180)
			(layer "F.Fab")
			(effects
				(font
					(size 1.27 1.27)
				)
			)
		)
		(duplicate_pad_numbers_are_jumpers no)
		(fp_line
			(start 0.7874 0.4064)
			(end -0.7874 0.4064)
			(stroke
				(width 0.1524)
				(type default)
			)
			(layer "F.SilkS")
		)
		(fp_line
			(start 0.7874 -0.4064)
			(end 0.7874 0.4064)
			(stroke
				(width 0.1524)
				(type default)
			)
			(layer "F.SilkS")
		)
		(fp_line
			(start -0.7874 0.4064)
			(end -0.7874 -0.4064)
			(stroke
				(width 0.1524)
				(type default)
			)
			(layer "F.SilkS")
		)
		(fp_line
			(start -0.7874 -0.4064)
			(end 0.7874 -0.4064)
			(stroke
				(width 0.1524)
				(type default)
			)
			(layer "F.SilkS")
		)
		(fp_line
			(start 0.67945 0.3048)
			(end 0.120396 0.3048)
			(stroke
				(width 0.1)
				(type default)
			)
			(layer "F.Fab")
		)
		(fp_line
			(start 0.67945 -0.3048)
			(end 0.67945 0.3048)
			(stroke
				(width 0.1)
				(type default)
			)
			(layer "F.Fab")
		)
		(fp_line
			(start 0.12065 -0.2794)
			(end 0.12065 -0.3048)
			(stroke
				(width 0.1)
				(type default)
			)
			(layer "F.Fab")
		)
		(fp_line
			(start 0.12065 -0.3048)
			(end 0.67945 -0.3048)
			(stroke
				(width 0.1)
				(type default)
			)
			(layer "F.Fab")
		)
		(fp_line
			(start 0.120396 0.3048)
			(end 0.120396 0.2794)
			(stroke
				(width 0.1)
				(type default)
			)
			(layer "F.Fab")
		)
		(fp_line
			(start 0.120396 0.2794)
			(end -0.12065 0.2794)
			(stroke
				(width 0.1)
				(type default)
			)
			(layer "F.Fab")
		)
		(fp_line
			(start -0.12065 0.3048)
			(end -0.67945 0.3048)
			(stroke
				(width 0.1)
				(type default)
			)
			(layer "F.Fab")
		)
		(fp_line
			(start -0.12065 0.2794)
			(end -0.12065 0.3048)
			(stroke
				(width 0.1)
				(type default)
			)
			(layer "F.Fab")
		)
		(fp_line
			(start -0.12065 -0.2794)
			(end 0.12065 -0.2794)
			(stroke
				(width 0.1)
				(type default)
			)
			(layer "F.Fab")
		)
		(fp_line
			(start -0.12065 -0.305054)
			(end -0.12065 -0.2794)
			(stroke
				(width 0.1)
				(type default)
			)
			(layer "F.Fab")
		)
		(fp_line
			(start -0.67945 0.3048)
			(end -0.67945 -0.305054)
			(stroke
				(width 0.1)
				(type default)
			)
			(layer "F.Fab")
		)
		(fp_line
			(start -0.67945 -0.305054)
			(end -0.12065 -0.305054)
			(stroke
				(width 0.1)
				(type default)
			)
			(layer "F.Fab")
		)
		(pad "1" smd circle
			(at -0.40005 0 180)
			(size 0 0)
			(layers "F.Cu" "F.Mask" "F.Paste")
			(net "P3V3_AUX")
		)
		(pad "2" smd circle
			(at 0.40005 0 180)
			(size 0 0)
			(layers "F.Cu" "F.Mask" "F.Paste")
			(net "OCP_SFF_WAKE_BUFF_N")
		)
	)
	(footprint ""
		(layer "F.Cu")
		(at 164.247576 -39.20363 180)
		(property "Reference" "R4456"
			(at 0 0 180)
			(layer "F.SilkS")
			(hide yes)
			(effects
				(font
					(size 1.27 1.27)
				)
			)
		)
		(property "Value" ""
			(at 0 0 180)
			(layer "F.Fab")
			(effects
				(font
					(size 1.27 1.27)
				)
			)
		)
		(duplicate_pad_numbers_are_jumpers no)
		(fp_line
			(start 0.7874 0.4064)
			(end -0.7874 0.4064)
			(stroke
				(width 0.1524)
				(type default)
			)
			(layer "F.SilkS")
		)
		(fp_line
			(start 0.7874 -0.4064)
			(end 0.7874 0.4064)
			(stroke
				(width 0.1524)
				(type default)
			)
			(layer "F.SilkS")
		)
		(fp_line
			(start -0.7874 0.4064)
			(end -0.7874 -0.4064)
			(stroke
				(width 0.1524)
				(type default)
			)
			(layer "F.SilkS")
		)
		(fp_line
			(start -0.7874 -0.4064)
			(end 0.7874 -0.4064)
			(stroke
				(width 0.1524)
				(type default)
			)
			(layer "F.SilkS")
		)
		(fp_line
			(start 0.67945 0.3048)
			(end 0.120396 0.3048)
			(stroke
				(width 0.1)
				(type default)
			)
			(layer "F.Fab")
		)
		(fp_line
			(start 0.67945 -0.3048)
			(end 0.67945 0.3048)
			(stroke
				(width 0.1)
				(type default)
			)
			(layer "F.Fab")
		)
		(fp_line
			(start 0.12065 -0.2794)
			(end 0.12065 -0.3048)
			(stroke
				(width 0.1)
				(type default)
			)
			(layer "F.Fab")
		)
		(fp_line
			(start 0.12065 -0.3048)
			(end 0.67945 -0.3048)
			(stroke
				(width 0.1)
				(type default)
			)
			(layer "F.Fab")
		)
		(fp_line
			(start 0.120396 0.3048)
			(end 0.120396 0.2794)
			(stroke
				(width 0.1)
				(type default)
			)
			(layer "F.Fab")
		)
		(fp_line
			(start 0.120396 0.2794)
			(end -0.12065 0.2794)
			(stroke
				(width 0.1)
				(type default)
			)
			(layer "F.Fab")
		)
		(fp_line
			(start -0.12065 0.3048)
			(end -0.67945 0.3048)
			(stroke
				(width 0.1)
				(type default)
			)
			(layer "F.Fab")
		)
		(fp_line
			(start -0.12065 0.2794)
			(end -0.12065 0.3048)
			(stroke
				(width 0.1)
				(type default)
			)
			(layer "F.Fab")
		)
		(fp_line
			(start -0.12065 -0.2794)
			(end 0.12065 -0.2794)
			(stroke
				(width 0.1)
				(type default)
			)
			(layer "F.Fab")
		)
		(fp_line
			(start -0.12065 -0.305054)
			(end -0.12065 -0.2794)
			(stroke
				(width 0.1)
				(type default)
			)
			(layer "F.Fab")
		)
		(fp_line
			(start -0.67945 0.3048)
			(end -0.67945 -0.305054)
			(stroke
				(width 0.1)
				(type default)
			)
			(layer "F.Fab")
		)
		(fp_line
			(start -0.67945 -0.305054)
			(end -0.12065 -0.305054)
			(stroke
				(width 0.1)
				(type default)
			)
			(layer "F.Fab")
		)
		(pad "1" smd circle
			(at -0.40005 0 180)
			(size 0 0)
			(layers "F.Cu" "F.Mask" "F.Paste")
			(net "P3V3_AUX")
		)
		(pad "2" smd circle
			(at 0.40005 0 180)
			(size 0 0)
			(layers "F.Cu" "F.Mask" "F.Paste")
			(net "USB_HUB_2_OVCUR1")
		)
	)
	(footprint ""
		(layer "F.Cu")
		(at 322.263516 -22.497288)
		(property "Reference" "R1455"
			(at 0 0 0)
			(layer "F.SilkS")
			(hide yes)
			(effects
				(font
					(size 1.27 1.27)
				)
			)
		)
		(property "Value" ""
			(at 0 0 0)
			(layer "F.Fab")
			(effects
				(font
					(size 1.27 1.27)
				)
			)
		)
		(duplicate_pad_numbers_are_jumpers no)
		(fp_line
			(start -0.7874 -0.4064)
			(end 0.7874 -0.4064)
			(stroke
				(width 0.1524)
				(type default)
			)
			(layer "F.SilkS")
		)
		(fp_line
			(start -0.7874 0.4064)
			(end -0.7874 -0.4064)
			(stroke
				(width 0.1524)
				(type default)
			)
			(layer "F.SilkS")
		)
		(fp_line
			(start 0.7874 -0.4064)
			(end 0.7874 0.4064)
			(stroke
				(width 0.1524)
				(type default)
			)
			(layer "F.SilkS")
		)
		(fp_line
			(start 0.7874 0.4064)
			(end -0.7874 0.4064)
			(stroke
				(width 0.1524)
				(type default)
			)
			(layer "F.SilkS")
		)
		(fp_line
			(start -0.67945 -0.305054)
			(end -0.12065 -0.305054)
			(stroke
				(width 0.1)
				(type default)
			)
			(layer "F.Fab")
		)
		(fp_line
			(start -0.67945 0.3048)
			(end -0.67945 -0.305054)
			(stroke
				(width 0.1)
				(type default)
			)
			(layer "F.Fab")
		)
		(fp_line
			(start -0.12065 -0.305054)
			(end -0.12065 -0.2794)
			(stroke
				(width 0.1)
				(type default)
			)
			(layer "F.Fab")
		)
		(fp_line
			(start -0.12065 -0.2794)
			(end 0.12065 -0.2794)
			(stroke
				(width 0.1)
				(type default)
			)
			(layer "F.Fab")
		)
		(fp_line
			(start -0.12065 0.2794)
			(end -0.12065 0.3048)
			(stroke
				(width 0.1)
				(type default)
			)
			(layer "F.Fab")
		)
		(fp_line
			(start -0.12065 0.3048)
			(end -0.67945 0.3048)
			(stroke
				(width 0.1)
				(type default)
			)
			(layer "F.Fab")
		)
		(fp_line
			(start 0.120396 0.2794)
			(end -0.12065 0.2794)
			(stroke
				(width 0.1)
				(type default)
			)
			(layer "F.Fab")
		)
		(fp_line
			(start 0.120396 0.3048)
			(end 0.120396 0.2794)
			(stroke
				(width 0.1)
				(type default)
			)
			(layer "F.Fab")
		)
		(fp_line
			(start 0.12065 -0.3048)
			(end 0.67945 -0.3048)
			(stroke
				(width 0.1)
				(type default)
			)
			(layer "F.Fab")
		)
		(fp_line
			(start 0.12065 -0.2794)
			(end 0.12065 -0.3048)
			(stroke
				(width 0.1)
				(type default)
			)
			(layer "F.Fab")
		)
		(fp_line
			(start 0.67945 -0.3048)
			(end 0.67945 0.3048)
			(stroke
				(width 0.1)
				(type default)
			)
			(layer "F.Fab")
		)
		(fp_line
			(start 0.67945 0.3048)
			(end 0.120396 0.3048)
			(stroke
				(width 0.1)
				(type default)
			)
			(layer "F.Fab")
		)
		(pad "1" smd circle
			(at -0.40005 0)
			(size 0 0)
			(layers "F.Cu" "F.Mask" "F.Paste")
			(net "FM_ADR_MODE0_R")
		)
		(pad "2" smd circle
			(at 0.40005 0)
			(size 0 0)
			(layers "F.Cu" "F.Mask" "F.Paste")
			(net "FM_ADR_MODE0")
		)
	)
	(footprint ""
		(layer "F.Cu")
		(at 106.3117 -256.6543 -90)
		(property "Reference" "C231"
			(at 0 0 270)
			(layer "F.SilkS")
			(hide yes)
			(effects
				(font
					(size 1.27 1.27)
				)
			)
		)
		(property "Value" ""
			(at 0 0 270)
			(layer "F.Fab")
			(effects
				(font
					(size 1.27 1.27)
				)
			)
		)
		(duplicate_pad_numbers_are_jumpers no)
		(fp_line
			(start -0.7874 0.4064)
			(end -0.7874 -0.4064)
			(stroke
				(width 0.1524)
				(type default)
			)
			(layer "F.SilkS")
		)
		(fp_line
			(start 0.7874 0.4064)
			(end -0.7874 0.4064)
			(stroke
				(width 0.1524)
				(type default)
			)
			(layer "F.SilkS")
		)
		(fp_line
			(start -0.7874 -0.4064)
			(end 0.7874 -0.4064)
			(stroke
				(width 0.1524)
				(type default)
			)
			(layer "F.SilkS")
		)
		(fp_line
			(start 0.7874 -0.4064)
			(end 0.7874 0.4064)
			(stroke
				(width 0.1524)
				(type default)
			)
			(layer "F.SilkS")
		)
		(fp_line
			(start -0.67945 0.3048)
			(end -0.67945 -0.305054)
			(stroke
				(width 0.1)
				(type default)
			)
			(layer "F.Fab")
		)
		(fp_line
			(start -0.12065 0.3048)
			(end -0.67945 0.3048)
			(stroke
				(width 0.1)
				(type default)
			)
			(layer "F.Fab")
		)
		(fp_line
			(start 0.120396 0.3048)
			(end 0.120396 0.2794)
			(stroke
				(width 0.1)
				(type default)
			)
			(layer "F.Fab")
		)
		(fp_line
			(start 0.67945 0.3048)
			(end 0.120396 0.3048)
			(stroke
				(width 0.1)
				(type default)
			)
			(layer "F.Fab")
		)
		(fp_line
			(start -0.12065 0.2794)
			(end -0.12065 0.3048)
			(stroke
				(width 0.1)
				(type default)
			)
			(layer "F.Fab")
		)
		(fp_line
			(start 0.120396 0.2794)
			(end -0.12065 0.2794)
			(stroke
				(width 0.1)
				(type default)
			)
			(layer "F.Fab")
		)
		(fp_line
			(start -0.12065 -0.2794)
			(end 0.12065 -0.2794)
			(stroke
				(width 0.1)
				(type default)
			)
			(layer "F.Fab")
		)
		(fp_line
			(start 0.12065 -0.2794)
			(end 0.12065 -0.3048)
			(stroke
				(width 0.1)
				(type default)
			)
			(layer "F.Fab")
		)
		(fp_line
			(start 0.12065 -0.3048)
			(end 0.67945 -0.3048)
			(stroke
				(width 0.1)
				(type default)
			)
			(layer "F.Fab")
		)
		(fp_line
			(start 0.67945 -0.3048)
			(end 0.67945 0.3048)
			(stroke
				(width 0.1)
				(type default)
			)
			(layer "F.Fab")
		)
		(fp_line
			(start -0.67945 -0.305054)
			(end -0.12065 -0.305054)
			(stroke
				(width 0.1)
				(type default)
			)
			(layer "F.Fab")
		)
		(fp_line
			(start -0.12065 -0.305054)
			(end -0.12065 -0.2794)
			(stroke
				(width 0.1)
				(type default)
			)
			(layer "F.Fab")
		)
		(pad "1" smd circle
			(at -0.40005 0 270)
			(size 0 0)
			(layers "F.Cu" "F.Mask" "F.Paste")
			(net "PVCCIN_CPU1")
		)
		(pad "2" smd circle
			(at 0.40005 0 270)
			(size 0 0)
			(layers "F.Cu" "F.Mask" "F.Paste")
			(net "GND")
		)
	)
	(footprint ""
		(layer "F.Cu")
		(at 367.44783 -244.03177 90)
		(property "Reference" "C1021"
			(at 0 0 90)
			(layer "F.SilkS")
			(hide yes)
			(effects
				(font
					(size 1.27 1.27)
				)
			)
		)
		(property "Value" ""
			(at 0 0 90)
			(layer "F.Fab")
			(effects
				(font
					(size 1.27 1.27)
				)
			)
		)
		(duplicate_pad_numbers_are_jumpers no)
		(fp_line
			(start 0.7874 -0.4064)
			(end 0.7874 0.4064)
			(stroke
				(width 0.1524)
				(type default)
			)
			(layer "F.SilkS")
		)
		(fp_line
			(start -0.7874 -0.4064)
			(end 0.7874 -0.4064)
			(stroke
				(width 0.1524)
				(type default)
			)
			(layer "F.SilkS")
		)
		(fp_line
			(start 0.7874 0.4064)
			(end -0.7874 0.4064)
			(stroke
				(width 0.1524)
				(type default)
			)
			(layer "F.SilkS")
		)
		(fp_line
			(start -0.7874 0.4064)
			(end -0.7874 -0.4064)
			(stroke
				(width 0.1524)
				(type default)
			)
			(layer "F.SilkS")
		)
		(fp_line
			(start -0.12065 -0.305054)
			(end -0.12065 -0.2794)
			(stroke
				(width 0.1)
				(type default)
			)
			(layer "F.Fab")
		)
		(fp_line
			(start -0.67945 -0.305054)
			(end -0.12065 -0.305054)
			(stroke
				(width 0.1)
				(type default)
			)
			(layer "F.Fab")
		)
		(fp_line
			(start 0.67945 -0.3048)
			(end 0.67945 0.3048)
			(stroke
				(width 0.1)
				(type default)
			)
			(layer "F.Fab")
		)
		(fp_line
			(start 0.12065 -0.3048)
			(end 0.67945 -0.3048)
			(stroke
				(width 0.1)
				(type default)
			)
			(layer "F.Fab")
		)
		(fp_line
			(start 0.12065 -0.2794)
			(end 0.12065 -0.3048)
			(stroke
				(width 0.1)
				(type default)
			)
			(layer "F.Fab")
		)
		(fp_line
			(start -0.12065 -0.2794)
			(end 0.12065 -0.2794)
			(stroke
				(width 0.1)
				(type default)
			)
			(layer "F.Fab")
		)
		(fp_line
			(start 0.120396 0.2794)
			(end -0.12065 0.2794)
			(stroke
				(width 0.1)
				(type default)
			)
			(layer "F.Fab")
		)
		(fp_line
			(start -0.12065 0.2794)
			(end -0.12065 0.3048)
			(stroke
				(width 0.1)
				(type default)
			)
			(layer "F.Fab")
		)
		(fp_line
			(start 0.67945 0.3048)
			(end 0.120396 0.3048)
			(stroke
				(width 0.1)
				(type default)
			)
			(layer "F.Fab")
		)
		(fp_line
			(start 0.120396 0.3048)
			(end 0.120396 0.2794)
			(stroke
				(width 0.1)
				(type default)
			)
			(layer "F.Fab")
		)
		(fp_line
			(start -0.12065 0.3048)
			(end -0.67945 0.3048)
			(stroke
				(width 0.1)
				(type default)
			)
			(layer "F.Fab")
		)
		(fp_line
			(start -0.67945 0.3048)
			(end -0.67945 -0.305054)
			(stroke
				(width 0.1)
				(type default)
			)
			(layer "F.Fab")
		)
		(pad "1" smd circle
			(at -0.40005 0 90)
			(size 0 0)
			(layers "F.Cu" "F.Mask" "F.Paste")
			(net "PVCCIN_CPU0")
		)
		(pad "2" smd circle
			(at 0.40005 0 90)
			(size 0 0)
			(layers "F.Cu" "F.Mask" "F.Paste")
			(net "GND")
		)
	)
	(footprint ""
		(layer "F.Cu")
		(at 193.95948 -350.510348 180)
		(property "Reference" "R1235"
			(at 0 0 180)
			(layer "F.SilkS")
			(hide yes)
			(effects
				(font
					(size 1.27 1.27)
				)
			)
		)
		(property "Value" ""
			(at 0 0 180)
			(layer "F.Fab")
			(effects
				(font
					(size 1.27 1.27)
				)
			)
		)
		(duplicate_pad_numbers_are_jumpers no)
		(fp_line
			(start 0.7874 0.4064)
			(end -0.7874 0.4064)
			(stroke
				(width 0.1524)
				(type default)
			)
			(layer "F.SilkS")
		)
		(fp_line
			(start 0.7874 -0.4064)
			(end 0.7874 0.4064)
			(stroke
				(width 0.1524)
				(type default)
			)
			(layer "F.SilkS")
		)
		(fp_line
			(start -0.7874 0.4064)
			(end -0.7874 -0.4064)
			(stroke
				(width 0.1524)
				(type default)
			)
			(layer "F.SilkS")
		)
		(fp_line
			(start -0.7874 -0.4064)
			(end 0.7874 -0.4064)
			(stroke
				(width 0.1524)
				(type default)
			)
			(layer "F.SilkS")
		)
		(fp_line
			(start 0.67945 0.3048)
			(end 0.120396 0.3048)
			(stroke
				(width 0.1)
				(type default)
			)
			(layer "F.Fab")
		)
		(fp_line
			(start 0.67945 -0.3048)
			(end 0.67945 0.3048)
			(stroke
				(width 0.1)
				(type default)
			)
			(layer "F.Fab")
		)
		(fp_line
			(start 0.12065 -0.2794)
			(end 0.12065 -0.3048)
			(stroke
				(width 0.1)
				(type default)
			)
			(layer "F.Fab")
		)
		(fp_line
			(start 0.12065 -0.3048)
			(end 0.67945 -0.3048)
			(stroke
				(width 0.1)
				(type default)
			)
			(layer "F.Fab")
		)
		(fp_line
			(start 0.120396 0.3048)
			(end 0.120396 0.2794)
			(stroke
				(width 0.1)
				(type default)
			)
			(layer "F.Fab")
		)
		(fp_line
			(start 0.120396 0.2794)
			(end -0.12065 0.2794)
			(stroke
				(width 0.1)
				(type default)
			)
			(layer "F.Fab")
		)
		(fp_line
			(start -0.12065 0.3048)
			(end -0.67945 0.3048)
			(stroke
				(width 0.1)
				(type default)
			)
			(layer "F.Fab")
		)
		(fp_line
			(start -0.12065 0.2794)
			(end -0.12065 0.3048)
			(stroke
				(width 0.1)
				(type default)
			)
			(layer "F.Fab")
		)
		(fp_line
			(start -0.12065 -0.2794)
			(end 0.12065 -0.2794)
			(stroke
				(width 0.1)
				(type default)
			)
			(layer "F.Fab")
		)
		(fp_line
			(start -0.12065 -0.305054)
			(end -0.12065 -0.2794)
			(stroke
				(width 0.1)
				(type default)
			)
			(layer "F.Fab")
		)
		(fp_line
			(start -0.67945 0.3048)
			(end -0.67945 -0.305054)
			(stroke
				(width 0.1)
				(type default)
			)
			(layer "F.Fab")
		)
		(fp_line
			(start -0.67945 -0.305054)
			(end -0.12065 -0.305054)
			(stroke
				(width 0.1)
				(type default)
			)
			(layer "F.Fab")
		)
		(pad "1" smd circle
			(at -0.40005 0 180)
			(size 0 0)
			(layers "F.Cu" "F.Mask" "F.Paste")
			(net "GND")
		)
		(pad "2" smd circle
			(at 0.40005 0 180)
			(size 0 0)
			(layers "F.Cu" "F.Mask" "F.Paste")
			(net "PUD_XTAL_CPU1_MODE0")
		)
	)
)
